#ISCELL
  mstr_misc dns *
  *
#ISCELL
  mstr_symbols intel_corp_bpage *
  *
#CELL
  mstr_discrete cap *
  page203_i1
#ISCELL
  mstr_symbols gnd *
  page203_i100
#CELL
  w_hdl sc2k2p50v3kx-gp *
  page203_i101
#CELL
  w_hdl 3d01r5f-gp *
  page203_i102
#ISCELL
  mstr_symbols gnd *
  page203_i103
#ISCELL
  mstr_symbols gnd *
  page203_i104
#CELL
  w_hdl 3d01r5f-gp *
  page203_i105
#CELL
  w_hdl sc2k2p50v3kx-gp *
  page203_i106
#ISCELL
  mstr_symbols gnd *
  page203_i107
#CELL
  mstr_discrete cap *
  page203_i108
#ISCELL
  mstr_symbols pvccin_cpu0 *
  page203_i109
#CELL
  mstr_discrete res *
  page203_i110
#CELL
  mstr_discrete res *
  page203_i111
#ISCELL
  mstr_symbols pvccin_cpu0 *
  page203_i12
#ISCELL
  mstr_symbols gnd *
  page203_i14
#CELL
  mstr_discrete inductor *
  page203_i15
#CELL
  mstr_discrete capp *
  page203_i16
#ISCELL
  mstr_symbols gnd *
  page203_i17
#CELL
  mstr_discrete capp *
  page203_i18
#ISCELL
  mstr_standard offpage *
  page203_i19
#CELL
  mstr_discrete cap *
  page203_i2
#ISCELL
  mstr_standard offpage *
  page203_i20
#ISCELL
  mstr_standard offpage *
  page203_i21
#CELL
  mstr_discrete inductor *
  page203_i24
#CELL
  dev_discrete cap_a *
  page203_i25
#ISCELL
  mstr_symbols gnd *
  page203_i26
#ISCELL
  mstr_symbols gnd *
  page203_i27
#CELL
  mstr_discrete capp *
  page203_i28
#CELL
  mstr_discrete capp *
  page203_i29
#CELL
  mstr_discrete cap *
  page203_i3
#CELL
  mstr_discrete capp *
  page203_i30
#CELL
  mstr_discrete capp *
  page203_i32
#ISCELL
  mstr_symbols pvccin_cpu0 *
  page203_i33
#CELL
  mstr_discrete capp *
  page203_i34
#CELL
  mstr_discrete res *
  page203_i38
#ISCELL
  mstr_symbols vcc_core *
  page203_i39
#CELL
  mstr_discrete cap *
  page203_i40
#CELL
  dev_discrete cap_a *
  page203_i41
#CELL
  mstr_discrete cap *
  page203_i42
#CELL
  mstr_discrete cap *
  page203_i45
#CELL
  dev_discrete cap_a *
  page203_i46
#CELL
  mstr_discrete cap *
  page203_i47
#CELL
  mstr_discrete cap *
  page203_i48
#CELL
  dev_discrete cap_a *
  page203_i49
#ISCELL
  mstr_standard offpage *
  page203_i5
#CELL
  mstr_discrete res *
  page203_i50
#CELL
  mstr_discrete cap *
  page203_i51
#CELL
  dev_discrete cap_a *
  page203_i52
#CELL
  mstr_discrete cap *
  page203_i53
#CELL
  mstr_discrete cap *
  page203_i54
#ISCELL
  mstr_standard offpage *
  page203_i55
#ISCELL
  mstr_symbols gnd *
  page203_i56
#CELL
  mstr_discrete cap *
  page203_i57
#CELL
  mstr_discrete cap *
  page203_i58
#CELL
  mstr_discrete cap *
  page203_i59
#ISCELL
  mstr_standard offpage *
  page203_i6
#ISCELL
  mstr_standard offpage *
  page203_i60
#ISCELL
  mstr_symbols vcc_core *
  page203_i61
#ISCELL
  mstr_symbols gnd *
  page203_i62
#ISCELL
  mstr_symbols gnd *
  page203_i63
#ISCELL
  mstr_symbols p5v_stby *
  page203_i64
#ISCELL
  mstr_symbols p5v_stby *
  page203_i65
#CELL
  dev_discrete cap_a *
  page203_i66
#CELL
  mstr_discrete res *
  page203_i67
#CELL
  dev_discrete cap_a *
  page203_i68
#CELL
  dev_discrete cap_a *
  page203_i69
#ISCELL
  mstr_standard offpage *
  page203_i7
#CELL
  mstr_discrete ir354xx *
  page203_i70
#CELL
  mstr_discrete ir354xx *
  page203_i71
#CELL
  mstr_discrete res *
  page203_i89
#ISCELL
  mstr_symbols gnd *
  page203_i90
#CELL
  mstr_discrete res *
  page203_i91
#ISCELL
  mstr_symbols gnd *
  page203_i92
#CELL
  dev_discrete cap_a *
  page203_i93
#ISCELL
  mstr_symbols gnd *
  page203_i94
#CELL
  dev_discrete cap_a *
  page203_i96
#ISCELL
  mstr_symbols gnd *
  page203_i97
#CELL
  mstr_discrete cap *
  page203_i99
